# S9S_MB_2U (Grand Teton) — schematic netlist excerpt (pin names and nets, part order shuffled) for the footprints in the layout excerpt that follows; sources: Cadence DE-HDL packaged netlist, KiCad conversion of 03242023_DA0F0TMBIJ0_F0T_Motherboard_J_brd_V01_OCP.brd

PC1348  Q_CAP  0.1UF 25V 10% X7R  pkg 0402  page 276 : A = GND ; B = PVCCINFAON_CPU0_VREF
R4559  Q_RES  100K 1% CHIP  pkg 0402LF  page 146 : A = SWB_HSC_PWRGD ; B = GND

(kicad_pcb
	(version 20260206)
	(generator "pcbnew")
	(generator_version "10.0")
	(general
		(thickness 1.6)
		(legacy_teardrops no)
	)
	(paper "A4")
	(title_block
		(title "03242023_DA0F0TMBIJ0_F0T_Motherboard_J_brd_V01_OCP.brd")
		(comment 1 "Grand Teton / footprints 3533-3534 of 6105")
	)
	(layers
		(0 "F.Cu" signal "TOP")
		(4 "In1.Cu" signal "GND")
		(6 "In2.Cu" signal "IN1")
		(8 "In3.Cu" signal "GND1")
		(10 "In4.Cu" signal "IN2")
		(12 "In5.Cu" signal "GND2")
		(14 "In6.Cu" signal "IN3")
		(16 "In7.Cu" signal "GND3")
		(18 "In8.Cu" signal "VCC")
		(20 "In9.Cu" signal "VCC1")
		(22 "In10.Cu" signal "GND4")
		(24 "In11.Cu" signal "IN4")
		(26 "In12.Cu" signal "GND5")
		(28 "In13.Cu" signal "IN5")
		(30 "In14.Cu" signal "GND6")
		(32 "In15.Cu" signal "IN6")
		(34 "In16.Cu" signal "GND7")
		(2 "B.Cu" signal "BOTTOM")
		(9 "F.Adhes" user "F.Adhesive")
		(11 "B.Adhes" user "B.Adhesive")
		(13 "F.Paste" user "Package Geometry/Pastemask Top")
		(15 "B.Paste" user "Package Geometry/Pastemask Bottom")
		(5 "F.SilkS" user "Ref Des/Silkscreen Top")
		(7 "B.SilkS" user "Ref Des/Silkscreen Bottom")
		(1 "F.Mask" user "Board Geometry/Soldermask Top")
		(3 "B.Mask" user "Board Geometry/Soldermask Bottom")
		(17 "Dwgs.User" user "User.Drawings")
		(19 "Cmts.User" user "User.Comments")
		(21 "Eco1.User" user "User.Eco1")
		(23 "Eco2.User" user "User.Eco2")
		(25 "Edge.Cuts" user "Board Geometry/Outline")
		(27 "Margin" user)
		(31 "F.CrtYd" user "Package Geometry/Place Bound Top")
		(29 "B.CrtYd" user "Package Geometry/Place Bound Bottom")
		(35 "F.Fab" user "Ref Des/Assembly Top")
		(33 "B.Fab" user "Ref Des/Assembly Bottom")
	)
	(footprint ""
		(layer "F.Cu")
		(at 356.616 -417.159948 180)
		(property "Reference" "R4559"
			(at 0 0 180)
			(layer "F.SilkS")
			(hide yes)
			(effects
				(font
					(size 1.27 1.27)
				)
			)
		)
		(property "Value" ""
			(at 0 0 180)
			(layer "F.Fab")
			(effects
				(font
					(size 1.27 1.27)
				)
			)
		)
		(duplicate_pad_numbers_are_jumpers no)
		(fp_line
			(start 0.7874 0.4064)
			(end -0.7874 0.4064)
			(stroke
				(width 0.1524)
				(type default)
			)
			(layer "F.SilkS")
		)
		(fp_line
			(start 0.7874 -0.4064)
			(end 0.7874 0.4064)
			(stroke
				(width 0.1524)
				(type default)
			)
			(layer "F.SilkS")
		)
		(fp_line
			(start -0.7874 0.4064)
			(end -0.7874 -0.4064)
			(stroke
				(width 0.1524)
				(type default)
			)
			(layer "F.SilkS")
		)
		(fp_line
			(start -0.7874 -0.4064)
			(end 0.7874 -0.4064)
			(stroke
				(width 0.1524)
				(type default)
			)
			(layer "F.SilkS")
		)
		(fp_line
			(start 0.67945 0.3048)
			(end 0.120396 0.3048)
			(stroke
				(width 0.1)
				(type default)
			)
			(layer "F.Fab")
		)
		(fp_line
			(start 0.67945 -0.3048)
			(end 0.67945 0.3048)
			(stroke
				(width 0.1)
				(type default)
			)
			(layer "F.Fab")
		)
		(fp_line
			(start 0.12065 -0.2794)
			(end 0.12065 -0.3048)
			(stroke
				(width 0.1)
				(type default)
			)
			(layer "F.Fab")
		)
		(fp_line
			(start 0.12065 -0.3048)
			(end 0.67945 -0.3048)
			(stroke
				(width 0.1)
				(type default)
			)
			(layer "F.Fab")
		)
		(fp_line
			(start 0.120396 0.3048)
			(end 0.120396 0.2794)
			(stroke
				(width 0.1)
				(type default)
			)
			(layer "F.Fab")
		)
		(fp_line
			(start 0.120396 0.2794)
			(end -0.12065 0.2794)
			(stroke
				(width 0.1)
				(type default)
			)
			(layer "F.Fab")
		)
		(fp_line
			(start -0.12065 0.3048)
			(end -0.67945 0.3048)
			(stroke
				(width 0.1)
				(type default)
			)
			(layer "F.Fab")
		)
		(fp_line
			(start -0.12065 0.2794)
			(end -0.12065 0.3048)
			(stroke
				(width 0.1)
				(type default)
			)
			(layer "F.Fab")
		)
		(fp_line
			(start -0.12065 -0.2794)
			(end 0.12065 -0.2794)
			(stroke
				(width 0.1)
				(type default)
			)
			(layer "F.Fab")
		)
		(fp_line
			(start -0.12065 -0.305054)
			(end -0.12065 -0.2794)
			(stroke
				(width 0.1)
				(type default)
			)
			(layer "F.Fab")
		)
		(fp_line
			(start -0.67945 0.3048)
			(end -0.67945 -0.305054)
			(stroke
				(width 0.1)
				(type default)
			)
			(layer "F.Fab")
		)
		(fp_line
			(start -0.67945 -0.305054)
			(end -0.12065 -0.305054)
			(stroke
				(width 0.1)
				(type default)
			)
			(layer "F.Fab")
		)
		(pad "1" smd circle
			(at -0.40005 0 180)
			(size 0 0)
			(layers "F.Cu" "F.Mask" "F.Paste")
			(net "SWB_HSC_PWRGD")
		)
		(pad "2" smd circle
			(at 0.40005 0 180)
			(size 0 0)
			(layers "F.Cu" "F.Mask" "F.Paste")
			(net "GND")
		)
	)
	(footprint ""
		(layer "F.Cu")
		(at 422.509188 -154.251914 180)
		(property "Reference" "PC1348"
			(at 0 0 180)
			(layer "F.SilkS")
			(hide yes)
			(effects
				(font
					(size 1.27 1.27)
				)
			)
		)
		(property "Value" ""
			(at 0 0 180)
			(layer "F.Fab")
			(effects
				(font
					(size 1.27 1.27)
				)
			)
		)
		(duplicate_pad_numbers_are_jumpers no)
		(fp_line
			(start 0.7874 0.4064)
			(end -0.7874 0.4064)
			(stroke
				(width 0.1524)
				(type default)
			)
			(layer "F.SilkS")
		)
		(fp_line
			(start 0.7874 -0.4064)
			(end 0.7874 0.4064)
			(stroke
				(width 0.1524)
				(type default)
			)
			(layer "F.SilkS")
		)
		(fp_line
			(start -0.7874 0.4064)
			(end -0.7874 -0.4064)
			(stroke
				(width 0.1524)
				(type default)
			)
			(layer "F.SilkS")
		)
		(fp_line
			(start -0.7874 -0.4064)
			(end 0.7874 -0.4064)
			(stroke
				(width 0.1524)
				(type default)
			)
			(layer "F.SilkS")
		)
		(fp_line
			(start 0.67945 0.3048)
			(end 0.120396 0.3048)
			(stroke
				(width 0.1)
				(type default)
			)
			(layer "F.Fab")
		)
		(fp_line
			(start 0.67945 -0.3048)
			(end 0.67945 0.3048)
			(stroke
				(width 0.1)
				(type default)
			)
			(layer "F.Fab")
		)
		(fp_line
			(start 0.12065 -0.2794)
			(end 0.12065 -0.3048)
			(stroke
				(width 0.1)
				(type default)
			)
			(layer "F.Fab")
		)
		(fp_line
			(start 0.12065 -0.3048)
			(end 0.67945 -0.3048)
			(stroke
				(width 0.1)
				(type default)
			)
			(layer "F.Fab")
		)
		(fp_line
			(start 0.120396 0.3048)
			(end 0.120396 0.2794)
			(stroke
				(width 0.1)
				(type default)
			)
			(layer "F.Fab")
		)
		(fp_line
			(start 0.120396 0.2794)
			(end -0.12065 0.2794)
			(stroke
				(width 0.1)
				(type default)
			)
			(layer "F.Fab")
		)
		(fp_line
			(start -0.12065 0.3048)
			(end -0.67945 0.3048)
			(stroke
				(width 0.1)
				(type default)
			)
			(layer "F.Fab")
		)
		(fp_line
			(start -0.12065 0.2794)
			(end -0.12065 0.3048)
			(stroke
				(width 0.1)
				(type default)
			)
			(layer "F.Fab")
		)
		(fp_line
			(start -0.12065 -0.2794)
			(end 0.12065 -0.2794)
			(stroke
				(width 0.1)
				(type default)
			)
			(layer "F.Fab")
		)
		(fp_line
			(start -0.12065 -0.305054)
			(end -0.12065 -0.2794)
			(stroke
				(width 0.1)
				(type default)
			)
			(layer "F.Fab")
		)
		(fp_line
			(start -0.67945 0.3048)
			(end -0.67945 -0.305054)
			(stroke
				(width 0.1)
				(type default)
			)
			(layer "F.Fab")
		)
		(fp_line
			(start -0.67945 -0.305054)
			(end -0.12065 -0.305054)
			(stroke
				(width 0.1)
				(type default)
			)
			(layer "F.Fab")
		)
		(pad "1" smd circle
			(at -0.40005 0 180)
			(size 0 0)
			(layers "F.Cu" "F.Mask" "F.Paste")
			(net "GND")
		)
		(pad "2" smd circle
			(at 0.40005 0 180)
			(size 0 0)
			(layers "F.Cu" "F.Mask" "F.Paste")
			(net "PVCCINFAON_CPU0_VREF")
		)
	)
)
